# SCM (Grand Teton) — schematic netlist excerpt (pin names and nets, part order shuffled) for the footprints in the layout excerpt that follows; sources: Cadence DE-HDL packaged netlist, KiCad conversion of 12092022_DA0F0TMDCD0_F0T_Management_Board_D_brd_V3_OCP.brd

D3  Q_LED  IC  pkg SMLF  page 47 : A = LED_POSTCODE_3_R ; C = GND
R558  Q_RES  4.7K 1% CHIP  pkg 0402LF  page 21 : A = P3V3_AUX ; B = SPI_BMC_CS1_FLASH_R_N

(kicad_pcb
	(version 20260206)
	(generator "pcbnew")
	(generator_version "10.0")
	(general
		(thickness 1.6)
		(legacy_teardrops no)
	)
	(paper "A4")
	(title_block
		(title "12092022_DA0F0TMDCD0_F0T_Management_Board_D_brd_V3_OCP.brd")
		(comment 1 "Grand Teton / footprints 182-183 of 1440")
	)
	(layers
		(0 "F.Cu" signal "TOP")
		(4 "In1.Cu" signal "GND")
		(6 "In2.Cu" signal "IN1")
		(8 "In3.Cu" signal "GND1")
		(10 "In4.Cu" signal "IN2")
		(12 "In5.Cu" signal "VCC")
		(14 "In6.Cu" signal "VCC1")
		(16 "In7.Cu" signal "IN3")
		(18 "In8.Cu" signal "GND2")
		(20 "In9.Cu" signal "IN4")
		(22 "In10.Cu" signal "GND3")
		(2 "B.Cu" signal "BOTTOM")
		(9 "F.Adhes" user "F.Adhesive")
		(11 "B.Adhes" user "B.Adhesive")
		(13 "F.Paste" user "Package Geometry/Pastemask Top")
		(15 "B.Paste" user "Package Geometry/Pastemask Bottom")
		(5 "F.SilkS" user "Ref Des/Silkscreen Top")
		(7 "B.SilkS" user "Ref Des/Silkscreen Bottom")
		(1 "F.Mask" user "Board Geometry/Soldermask Top")
		(3 "B.Mask" user "Board Geometry/Soldermask Bottom")
		(17 "Dwgs.User" user "User.Drawings")
		(19 "Cmts.User" user "User.Comments")
		(21 "Eco1.User" user "User.Eco1")
		(23 "Eco2.User" user "User.Eco2")
		(25 "Edge.Cuts" user "Board Geometry/Outline")
		(27 "Margin" user)
		(31 "F.CrtYd" user "Package Geometry/Place Bound Top")
		(29 "B.CrtYd" user "Package Geometry/Place Bound Bottom")
		(35 "F.Fab" user "Ref Des/Assembly Top")
		(33 "B.Fab" user "Ref Des/Assembly Bottom")
	)
	(footprint ""
		(layer "F.Cu")
		(at 74.01052 -27.738832 90)
		(property "Reference" "D3"
			(at -1.830832 8.94715 90)
			(unlocked yes)
			(layer "F.SilkS")
			(effects
				(font
					(size 0.7874 0.5842)
					(thickness 0.1524)
				)
				(justify left)
			)
		)
		(property "Value" ""
			(at 0 0 90)
			(layer "F.Fab")
			(effects
				(font
					(size 1.27 1.27)
				)
			)
		)
		(duplicate_pad_numbers_are_jumpers no)
		(fp_line
			(start 1.778 -0.5588)
			(end 1.3208 -0.5588)
			(stroke
				(width 0.1524)
				(type default)
			)
			(layer "F.SilkS")
		)
		(fp_line
			(start 1.778 -0.5588)
			(end 1.778 0.5588)
			(stroke
				(width 0.1524)
				(type default)
			)
			(layer "F.SilkS")
		)
		(fp_line
			(start 1.4732 -0.5588)
			(end 1.4732 0.5588)
			(stroke
				(width 0.1524)
				(type default)
			)
			(layer "F.SilkS")
		)
		(fp_line
			(start 1.3208 -0.5588)
			(end 1.3208 0.5588)
			(stroke
				(width 0.1524)
				(type default)
			)
			(layer "F.SilkS")
		)
		(fp_line
			(start -1.3208 -0.5588)
			(end 1.3208 -0.5588)
			(stroke
				(width 0.1524)
				(type default)
			)
			(layer "F.SilkS")
		)
		(fp_line
			(start 1.778 0.5588)
			(end 1.3208 0.5588)
			(stroke
				(width 0.1524)
				(type default)
			)
			(layer "F.SilkS")
		)
		(fp_line
			(start 1.6256 0.5588)
			(end 1.6256 -0.5588)
			(stroke
				(width 0.1524)
				(type default)
			)
			(layer "F.SilkS")
		)
		(fp_line
			(start 1.3208 0.5588)
			(end -1.3208 0.5588)
			(stroke
				(width 0.1524)
				(type default)
			)
			(layer "F.SilkS")
		)
		(fp_line
			(start -1.3208 0.5588)
			(end -1.3208 -0.5588)
			(stroke
				(width 0.1524)
				(type default)
			)
			(layer "F.SilkS")
		)
		(fp_line
			(start 1.236726 -0.508)
			(end 1.1684 -0.508)
			(stroke
				(width 0.1)
				(type default)
			)
			(layer "F.Fab")
		)
		(fp_line
			(start 1.1684 -0.508)
			(end -1.1684 -0.508)
			(stroke
				(width 0.1)
				(type default)
			)
			(layer "F.Fab")
		)
		(fp_line
			(start -1.1684 -0.508)
			(end -1.235964 -0.508)
			(stroke
				(width 0.1)
				(type default)
			)
			(layer "F.Fab")
		)
		(fp_line
			(start -1.235964 -0.508)
			(end -1.235964 0.508)
			(stroke
				(width 0.1)
				(type default)
			)
			(layer "F.Fab")
		)
		(fp_line
			(start 1.236726 0.508)
			(end 1.236726 -0.508)
			(stroke
				(width 0.1)
				(type default)
			)
			(layer "F.Fab")
		)
		(fp_line
			(start 1.1684 0.508)
			(end 1.236726 0.508)
			(stroke
				(width 0.1)
				(type default)
			)
			(layer "F.Fab")
		)
		(fp_line
			(start -1.1684 0.508)
			(end 1.1684 0.508)
			(stroke
				(width 0.1)
				(type default)
			)
			(layer "F.Fab")
		)
		(fp_line
			(start -1.235964 0.508)
			(end -1.1684 0.508)
			(stroke
				(width 0.1)
				(type default)
			)
			(layer "F.Fab")
		)
		(fp_text user "+"
			(at -1.526032 -1.43637 90)
			(unlocked yes)
			(layer "F.SilkS")
			(effects
				(font
					(size 1.905 1.4224)
					(thickness 0.1524)
				)
				(justify left)
			)
		)
		(fp_text user "-"
			(at 0.328168 -1.10617 90)
			(unlocked yes)
			(layer "F.SilkS")
			(effects
				(font
					(size 1.905 1.4224)
					(thickness 0.1524)
				)
				(justify left)
			)
		)
		(fp_text user "-"
			(at 1.524 -0.24765 90)
			(unlocked yes)
			(layer "F.Fab")
			(effects
				(font
					(size 1.905 1.4224)
					(thickness 0.1524)
				)
				(justify left)
			)
		)
		(fp_text user "+"
			(at -2.5654 -0.24765 90)
			(unlocked yes)
			(layer "F.Fab")
			(effects
				(font
					(size 1.905 1.4224)
					(thickness 0.1524)
				)
				(justify left)
			)
		)
		(pad "A" smd rect
			(at -0.750062 0 90)
			(size 0.8128 0.8128)
			(layers "F.Cu" "F.Mask" "F.Paste")
			(net "LED_POSTCODE_3_R")
		)
		(pad "C" smd rect
			(at 0.750062 0 90)
			(size 0.8128 0.8128)
			(layers "F.Cu" "F.Mask" "F.Paste")
			(net "GND")
		)
	)
	(footprint ""
		(layer "F.Cu")
		(at 39.8272 -78.6638 180)
		(property "Reference" "R558"
			(at 0 0 180)
			(layer "F.SilkS")
			(hide yes)
			(effects
				(font
					(size 1.27 1.27)
				)
			)
		)
		(property "Value" ""
			(at 0 0 180)
			(layer "F.Fab")
			(effects
				(font
					(size 1.27 1.27)
				)
			)
		)
		(duplicate_pad_numbers_are_jumpers no)
		(fp_line
			(start 0.7874 0.4064)
			(end -0.7874 0.4064)
			(stroke
				(width 0.1524)
				(type default)
			)
			(layer "F.SilkS")
		)
		(fp_line
			(start 0.7874 -0.4064)
			(end 0.7874 0.4064)
			(stroke
				(width 0.1524)
				(type default)
			)
			(layer "F.SilkS")
		)
		(fp_line
			(start -0.7874 0.4064)
			(end -0.7874 -0.4064)
			(stroke
				(width 0.1524)
				(type default)
			)
			(layer "F.SilkS")
		)
		(fp_line
			(start -0.7874 -0.4064)
			(end 0.7874 -0.4064)
			(stroke
				(width 0.1524)
				(type default)
			)
			(layer "F.SilkS")
		)
		(fp_line
			(start 0.67945 0.3048)
			(end 0.120396 0.3048)
			(stroke
				(width 0.1)
				(type default)
			)
			(layer "F.Fab")
		)
		(fp_line
			(start 0.67945 -0.3048)
			(end 0.67945 0.3048)
			(stroke
				(width 0.1)
				(type default)
			)
			(layer "F.Fab")
		)
		(fp_line
			(start 0.12065 -0.2794)
			(end 0.12065 -0.3048)
			(stroke
				(width 0.1)
				(type default)
			)
			(layer "F.Fab")
		)
		(fp_line
			(start 0.12065 -0.3048)
			(end 0.67945 -0.3048)
			(stroke
				(width 0.1)
				(type default)
			)
			(layer "F.Fab")
		)
		(fp_line
			(start 0.120396 0.3048)
			(end 0.120396 0.2794)
			(stroke
				(width 0.1)
				(type default)
			)
			(layer "F.Fab")
		)
		(fp_line
			(start 0.120396 0.2794)
			(end -0.12065 0.2794)
			(stroke
				(width 0.1)
				(type default)
			)
			(layer "F.Fab")
		)
		(fp_line
			(start -0.12065 0.3048)
			(end -0.67945 0.3048)
			(stroke
				(width 0.1)
				(type default)
			)
			(layer "F.Fab")
		)
		(fp_line
			(start -0.12065 0.2794)
			(end -0.12065 0.3048)
			(stroke
				(width 0.1)
				(type default)
			)
			(layer "F.Fab")
		)
		(fp_line
			(start -0.12065 -0.2794)
			(end 0.12065 -0.2794)
			(stroke
				(width 0.1)
				(type default)
			)
			(layer "F.Fab")
		)
		(fp_line
			(start -0.12065 -0.305054)
			(end -0.12065 -0.2794)
			(stroke
				(width 0.1)
				(type default)
			)
			(layer "F.Fab")
		)
		(fp_line
			(start -0.67945 0.3048)
			(end -0.67945 -0.305054)
			(stroke
				(width 0.1)
				(type default)
			)
			(layer "F.Fab")
		)
		(fp_line
			(start -0.67945 -0.305054)
			(end -0.12065 -0.305054)
			(stroke
				(width 0.1)
				(type default)
			)
			(layer "F.Fab")
		)
		(pad "1" smd circle
			(at -0.40005 0 180)
			(size 0 0)
			(layers "F.Cu" "F.Mask" "F.Paste")
			(net "P3V3_AUX")
		)
		(pad "2" smd circle
			(at 0.40005 0 180)
			(size 0 0)
			(layers "F.Cu" "F.Mask" "F.Paste")
			(net "SPI_BMC_CS1_FLASH_R_N")
		)
	)
)
